(kicad_pcb
	(version 20260206)
	(generator "pcbnew")
	(generator_version "10.0")
	(general
		(thickness 1.6)
		(legacy_teardrops no)
	)
	(paper "A4")
	(title_block
		(title "01162023_DA0F0TEBIF0_F0T_Expander_BD_F_brd_V02_OCP.brd")
		(comment 1 "Grand Teton / footprints 4513-4517 of 9728")
	)
	(layers
		(0 "F.Cu" signal "TOP")
		(4 "In1.Cu" signal "GND")
		(6 "In2.Cu" signal "VCC")
		(8 "In3.Cu" signal "VCC1")
		(10 "In4.Cu" signal "GND1")
		(12 "In5.Cu" signal "IN1")
		(14 "In6.Cu" signal "GND2")
		(16 "In7.Cu" signal "IN2")
		(18 "In8.Cu" signal "GND3")
		(20 "In9.Cu" signal "IN3")
		(22 "In10.Cu" signal "GND4")
		(24 "In11.Cu" signal "IN4")
		(26 "In12.Cu" signal "GND5")
		(28 "In13.Cu" signal "IN5")
		(30 "In14.Cu" signal "GND6")
		(32 "In15.Cu" signal "IN6")
		(34 "In16.Cu" signal "GND7")
		(2 "B.Cu" signal "BOTTOM")
		(9 "F.Adhes" user "F.Adhesive")
		(11 "B.Adhes" user "B.Adhesive")
		(13 "F.Paste" user "Package Geometry/Pastemask Top")
		(15 "B.Paste" user "Package Geometry/Pastemask Bottom")
		(5 "F.SilkS" user "Ref Des/Silkscreen Top")
		(7 "B.SilkS" user "Ref Des/Silkscreen Bottom")
		(1 "F.Mask" user "Board Geometry/Soldermask Top")
		(3 "B.Mask" user "Board Geometry/Soldermask Bottom")
		(17 "Dwgs.User" user "User.Drawings")
		(19 "Cmts.User" user "User.Comments")
		(21 "Eco1.User" user "User.Eco1")
		(23 "Eco2.User" user "User.Eco2")
		(25 "Edge.Cuts" user "Board Geometry/Outline")
		(27 "Margin" user)
		(31 "F.CrtYd" user "Package Geometry/Place Bound Top")
		(29 "B.CrtYd" user "Package Geometry/Place Bound Bottom")
		(35 "F.Fab" user "Ref Des/Assembly Top")
		(33 "B.Fab" user "Ref Des/Assembly Bottom")
	)
	(footprint ""
		(layer "F.Cu")
		(at 195.699888 -378.70003)
		(property "Reference" "H80"
			(at -5.748528 -8.024368 0)
			(unlocked yes)
			(layer "F.SilkS")
			(effects
				(font
					(size 0.7874 0.5842)
					(thickness 0.1524)
				)
				(justify left)
			)
		)
		(property "Value" ""
			(at 0 0 0)
			(layer "F.Fab")
			(effects
				(font
					(size 1.27 1.27)
				)
			)
		)
		(duplicate_pad_numbers_are_jumpers no)
		(fp_arc
			(start 3.237738 7.315454)
			(mid -7.629888 2.404398)
			(end -1.540764 -7.84987)
			(stroke
				(width 0.1524)
				(type default)
			)
			(layer "F.SilkS")
		)
		(fp_arc
			(start 5.216906 -6.064758)
			(mid 7.270957 -3.336409)
			(end 7.999984 0)
			(stroke
				(width 0.1524)
				(type default)
			)
			(layer "F.SilkS")
		)
		(fp_arc
			(start 7.999984 0)
			(mid 7.276035 3.325462)
			(end 5.235194 6.04901)
			(stroke
				(width 0.1524)
				(type default)
			)
			(layer "F.SilkS")
		)
		(fp_arc
			(start 2.386838 7.635748)
			(mid -7.745564 2.008288)
			(end -1.623822 -7.83336)
			(stroke
				(width 0.1524)
				(type default)
			)
			(layer "B.SilkS")
		)
		(fp_arc
			(start 4.790694 6.40715)
			(mid 4.299861 6.746338)
			(end 3.785108 7.047992)
			(stroke
				(width 0.1524)
				(type default)
			)
			(layer "B.SilkS")
		)
		(fp_arc
			(start 5.308854 -5.984748)
			(mid 7.296334 -3.281019)
			(end 7.999984 0)
			(stroke
				(width 0.1524)
				(type default)
			)
			(layer "B.SilkS")
		)
		(fp_arc
			(start 7.999984 0)
			(mid 7.44841 2.918885)
			(end 5.86994 5.435346)
			(stroke
				(width 0.1524)
				(type default)
			)
			(layer "B.SilkS")
		)
		(fp_circle
			(center 0 0)
			(end 7.999984 0)
			(stroke
				(width 0.1)
				(type default)
			)
			(fill no)
			(layer "B.Fab")
		)
		(fp_circle
			(center 0 0)
			(end 7.999984 0)
			(stroke
				(width 0.1)
				(type default)
			)
			(fill no)
			(layer "F.Fab")
		)
		(pad "" np_thru_hole circle
			(at 0 0)
			(size 3.4036 3.4036)
			(drill 3.4036)
			(layers "*.Cu" "*.Mask")
			(clearance 0.381)
			(thermal_gap 0.381)
		)
		(pad "2" thru_hole circle
			(at 3.606292 0)
			(size 0.762 0.762)
			(drill 0.5588)
			(layers "*.Cu" "*.Mask")
			(remove_unused_layers no)
			(net "GND")
			(clearance 0.1524)
			(thermal_gap 0.1524)
		)
		(pad "3" thru_hole circle
			(at 2.549906 -2.549906)
			(size 0.762 0.762)
			(drill 0.5588)
			(layers "*.Cu" "*.Mask")
			(remove_unused_layers no)
			(net "GND")
			(clearance 0.1524)
			(thermal_gap 0.1524)
		)
		(pad "4" thru_hole circle
			(at 0 -3.606292)
			(size 0.762 0.762)
			(drill 0.5588)
			(layers "*.Cu" "*.Mask")
			(remove_unused_layers no)
			(net "GND")
			(clearance 0.1524)
			(thermal_gap 0.1524)
		)
		(pad "5" thru_hole circle
			(at -2.549906 -2.549906)
			(size 0.762 0.762)
			(drill 0.5588)
			(layers "*.Cu" "*.Mask")
			(remove_unused_layers no)
			(net "GND")
			(clearance 0.1524)
			(thermal_gap 0.1524)
		)
		(pad "6" thru_hole circle
			(at -3.606292 0)
			(size 0.762 0.762)
			(drill 0.5588)
			(layers "*.Cu" "*.Mask")
			(remove_unused_layers no)
			(net "GND")
			(clearance 0.1524)
			(thermal_gap 0.1524)
		)
		(pad "7" thru_hole circle
			(at -2.549906 2.549906)
			(size 0.762 0.762)
			(drill 0.5588)
			(layers "*.Cu" "*.Mask")
			(remove_unused_layers no)
			(net "GND")
			(clearance 0.1524)
			(thermal_gap 0.1524)
		)
		(pad "8" thru_hole circle
			(at 0 3.606292)
			(size 0.762 0.762)
			(drill 0.5588)
			(layers "*.Cu" "*.Mask")
			(remove_unused_layers no)
			(net "GND")
			(clearance 0.1524)
			(thermal_gap 0.1524)
		)
		(pad "9" thru_hole circle
			(at 2.549906 2.549906)
			(size 0.762 0.762)
			(drill 0.5588)
			(layers "*.Cu" "*.Mask")
			(remove_unused_layers no)
			(net "GND")
			(clearance 0.1524)
			(thermal_gap 0.1524)
		)
		(zone
			(layer "F.Cu")
			(hatch none 0.5)
			(connect_pads
				(clearance 0)
			)
			(min_thickness 0.25)
			(keepout
				(tracks not_allowed)
				(vias allowed)
				(pads allowed)
				(copperpour not_allowed)
				(footprints allowed)
			)
			(placement
				(enabled no)
				(sheetname "")
			)
			(fill
				(thermal_gap 0.5)
				(thermal_bridge_width 0.5)
				(island_removal_mode 0)
			)
			(polygon
				(pts
					(arc
						(start 195.699888 -370.700046)
						(mid 187.699904 -378.70003)
						(end 195.699888 -386.700014)
					)
					(arc
						(start 195.699888 -383.95402)
						(mid 190.445898 -378.70003)
						(end 195.699888 -373.44604)
					)
				)
			)
		)
		(zone
			(layer "F.Cu")
			(hatch none 0.5)
			(connect_pads
				(clearance 0)
			)
			(min_thickness 0.25)
			(keepout
				(tracks not_allowed)
				(vias allowed)
				(pads allowed)
				(copperpour not_allowed)
				(footprints allowed)
			)
			(placement
				(enabled no)
				(sheetname "")
			)
			(fill
				(thermal_gap 0.5)
				(thermal_bridge_width 0.5)
				(island_removal_mode 0)
			)
			(polygon
				(pts
					(arc
						(start 195.699888 -370.700046)
						(mid 203.699872 -378.70003)
						(end 195.699888 -386.700014)
					)
					(arc
						(start 195.699888 -383.95402)
						(mid 200.953878 -378.70003)
						(end 195.699888 -373.44604)
					)
				)
			)
		)
		(zone
			(layers "F.Cu" "B.Cu" "In1.Cu" "In2.Cu" "In3.Cu" "In4.Cu" "In5.Cu" "In6.Cu"
				"In7.Cu" "In8.Cu" "In9.Cu" "In10.Cu" "In11.Cu" "In12.Cu" "In13.Cu" "In14.Cu"
				"In15.Cu" "In16.Cu"
			)
			(hatch none 0.5)
			(connect_pads
				(clearance 0)
			)
			(min_thickness 0.25)
			(keepout
				(tracks not_allowed)
				(vias allowed)
				(pads allowed)
				(copperpour not_allowed)
				(footprints allowed)
			)
			(placement
				(enabled no)
				(sheetname "")
			)
			(fill
				(thermal_gap 0.5)
				(thermal_bridge_width 0.5)
				(island_removal_mode 0)
			)
			(polygon
				(pts
					(arc
						(start 197.909688 -378.70003)
						(mid 193.490088 -378.70003)
						(end 197.909688 -378.70003)
					)
				)
			)
		)
		(zone
			(layer "B.Cu")
			(hatch none 0.5)
			(connect_pads
				(clearance 0)
			)
			(min_thickness 0.25)
			(keepout
				(tracks not_allowed)
				(vias allowed)
				(pads allowed)
				(copperpour not_allowed)
				(footprints allowed)
			)
			(placement
				(enabled no)
				(sheetname "")
			)
			(fill
				(thermal_gap 0.5)
				(thermal_bridge_width 0.5)
				(island_removal_mode 0)
			)
			(polygon
				(pts
					(arc
						(start 195.699888 -373.19204)
						(mid 190.191898 -378.70003)
						(end 195.699888 -384.20802)
					)
					(arc
						(start 195.699888 -383.72542)
						(mid 190.674498 -378.70003)
						(end 195.699888 -373.67464)
					)
				)
			)
		)
		(zone
			(layer "B.Cu")
			(hatch none 0.5)
			(connect_pads
				(clearance 0)
			)
			(min_thickness 0.25)
			(keepout
				(tracks not_allowed)
				(vias allowed)
				(pads allowed)
				(copperpour not_allowed)
				(footprints allowed)
			)
			(placement
				(enabled no)
				(sheetname "")
			)
			(fill
				(thermal_gap 0.5)
				(thermal_bridge_width 0.5)
				(island_removal_mode 0)
			)
			(polygon
				(pts
					(arc
						(start 195.699888 -373.19204)
						(mid 201.207878 -378.70003)
						(end 195.699888 -384.20802)
					)
					(arc
						(start 195.699888 -383.72542)
						(mid 200.725278 -378.70003)
						(end 195.699888 -373.67464)
					)
				)
			)
		)
	)
	(footprint ""
		(layer "F.Cu")
		(at 104.309672 -280.44902 -90)
		(property "Reference" "PC66"
			(at 0 0 270)
			(layer "F.SilkS")
			(hide yes)
			(effects
				(font
					(size 1.27 1.27)
				)
			)
		)
		(property "Value" ""
			(at 0 0 270)
			(layer "F.Fab")
			(effects
				(font
					(size 1.27 1.27)
				)
			)
		)
		(duplicate_pad_numbers_are_jumpers no)
		(fp_line
			(start -0.7874 0.4064)
			(end -0.7874 -0.4064)
			(stroke
				(width 0.1524)
				(type default)
			)
			(layer "F.SilkS")
		)
		(fp_line
			(start 0.7874 0.4064)
			(end -0.7874 0.4064)
			(stroke
				(width 0.1524)
				(type default)
			)
			(layer "F.SilkS")
		)
		(fp_line
			(start -0.7874 -0.4064)
			(end 0.7874 -0.4064)
			(stroke
				(width 0.1524)
				(type default)
			)
			(layer "F.SilkS")
		)
		(fp_line
			(start 0.7874 -0.4064)
			(end 0.7874 0.4064)
			(stroke
				(width 0.1524)
				(type default)
			)
			(layer "F.SilkS")
		)
		(fp_line
			(start -0.67945 0.3048)
			(end -0.67945 -0.305054)
			(stroke
				(width 0.1)
				(type default)
			)
			(layer "F.Fab")
		)
		(fp_line
			(start -0.12065 0.3048)
			(end -0.67945 0.3048)
			(stroke
				(width 0.1)
				(type default)
			)
			(layer "F.Fab")
		)
		(fp_line
			(start 0.120396 0.3048)
			(end 0.120396 0.2794)
			(stroke
				(width 0.1)
				(type default)
			)
			(layer "F.Fab")
		)
		(fp_line
			(start 0.67945 0.3048)
			(end 0.120396 0.3048)
			(stroke
				(width 0.1)
				(type default)
			)
			(layer "F.Fab")
		)
		(fp_line
			(start -0.12065 0.2794)
			(end -0.12065 0.3048)
			(stroke
				(width 0.1)
				(type default)
			)
			(layer "F.Fab")
		)
		(fp_line
			(start 0.120396 0.2794)
			(end -0.12065 0.2794)
			(stroke
				(width 0.1)
				(type default)
			)
			(layer "F.Fab")
		)
		(fp_line
			(start -0.12065 -0.2794)
			(end 0.12065 -0.2794)
			(stroke
				(width 0.1)
				(type default)
			)
			(layer "F.Fab")
		)
		(fp_line
			(start 0.12065 -0.2794)
			(end 0.12065 -0.3048)
			(stroke
				(width 0.1)
				(type default)
			)
			(layer "F.Fab")
		)
		(fp_line
			(start 0.12065 -0.3048)
			(end 0.67945 -0.3048)
			(stroke
				(width 0.1)
				(type default)
			)
			(layer "F.Fab")
		)
		(fp_line
			(start 0.67945 -0.3048)
			(end 0.67945 0.3048)
			(stroke
				(width 0.1)
				(type default)
			)
			(layer "F.Fab")
		)
		(fp_line
			(start -0.67945 -0.305054)
			(end -0.12065 -0.305054)
			(stroke
				(width 0.1)
				(type default)
			)
			(layer "F.Fab")
		)
		(fp_line
			(start -0.12065 -0.305054)
			(end -0.12065 -0.2794)
			(stroke
				(width 0.1)
				(type default)
			)
			(layer "F.Fab")
		)
		(pad "1" smd circle
			(at -0.40005 0 270)
			(size 0 0)
			(layers "F.Cu" "F.Mask" "F.Paste")
			(net "SW_P0V8_PEX0_PHASE1")
		)
		(pad "2" smd circle
			(at 0.40005 0 270)
			(size 0 0)
			(layers "F.Cu" "F.Mask" "F.Paste")
			(net "SW_P0V8_PEX0_BOOT1_R")
		)
	)
	(footprint ""
		(layer "F.Cu")
		(at 461.924908 -307.607716)
		(property "Reference" "PJ16"
			(at 0 0 0)
			(layer "F.SilkS")
			(hide yes)
			(effects
				(font
					(size 1.27 1.27)
				)
			)
		)
		(property "Value" ""
			(at 0 0 0)
			(layer "F.Fab")
			(effects
				(font
					(size 1.27 1.27)
				)
			)
		)
		(duplicate_pad_numbers_are_jumpers no)
		(pad "1" smd circle
			(at -0.40005 0 90)
			(size 0 0)
			(layers "F.Cu" "F.Mask" "F.Paste")
			(net "SH_P1V25_PEX3_FB_N")
		)
		(pad "2" smd rect
			(at 0.40005 0 180)
			(size 0.4572 0.508)
			(layers "F.Cu" "F.Mask" "F.Paste")
			(net "GND")
		)
		(zone
			(layer "F.Cu")
			(hatch none 0.5)
			(connect_pads
				(clearance 0)
			)
			(min_thickness 0.25)
			(keepout
				(tracks allowed)
				(vias not_allowed)
				(pads allowed)
				(copperpour not_allowed)
				(footprints allowed)
			)
			(placement
				(enabled no)
				(sheetname "")
			)
			(fill
				(thermal_gap 0.5)
				(thermal_bridge_width 0.5)
				(island_removal_mode 0)
			)
			(polygon
				(pts
					(xy 461.239108 -307.302916) (xy 462.610708 -307.302916) (xy 462.610708 -307.912516) (xy 461.239108 -307.912516)
				)
			)
		)
	)
	(footprint ""
		(layer "F.Cu")
		(at 331.489812 -72.766682 90)
		(property "Reference" "PR7084"
			(at 0 0 90)
			(layer "F.SilkS")
			(hide yes)
			(effects
				(font
					(size 1.27 1.27)
				)
			)
		)
		(property "Value" ""
			(at 0 0 90)
			(layer "F.Fab")
			(effects
				(font
					(size 1.27 1.27)
				)
			)
		)
		(duplicate_pad_numbers_are_jumpers no)
		(fp_line
			(start 0.7874 -0.4064)
			(end 0.7874 0.4064)
			(stroke
				(width 0.1524)
				(type default)
			)
			(layer "F.SilkS")
		)
		(fp_line
			(start -0.7874 -0.4064)
			(end 0.7874 -0.4064)
			(stroke
				(width 0.1524)
				(type default)
			)
			(layer "F.SilkS")
		)
		(fp_line
			(start 0.7874 0.4064)
			(end -0.7874 0.4064)
			(stroke
				(width 0.1524)
				(type default)
			)
			(layer "F.SilkS")
		)
		(fp_line
			(start -0.7874 0.4064)
			(end -0.7874 -0.4064)
			(stroke
				(width 0.1524)
				(type default)
			)
			(layer "F.SilkS")
		)
		(fp_line
			(start -0.12065 -0.305054)
			(end -0.12065 -0.2794)
			(stroke
				(width 0.1)
				(type default)
			)
			(layer "F.Fab")
		)
		(fp_line
			(start -0.67945 -0.305054)
			(end -0.12065 -0.305054)
			(stroke
				(width 0.1)
				(type default)
			)
			(layer "F.Fab")
		)
		(fp_line
			(start 0.67945 -0.3048)
			(end 0.67945 0.3048)
			(stroke
				(width 0.1)
				(type default)
			)
			(layer "F.Fab")
		)
		(fp_line
			(start 0.12065 -0.3048)
			(end 0.67945 -0.3048)
			(stroke
				(width 0.1)
				(type default)
			)
			(layer "F.Fab")
		)
		(fp_line
			(start 0.12065 -0.2794)
			(end 0.12065 -0.3048)
			(stroke
				(width 0.1)
				(type default)
			)
			(layer "F.Fab")
		)
		(fp_line
			(start -0.12065 -0.2794)
			(end 0.12065 -0.2794)
			(stroke
				(width 0.1)
				(type default)
			)
			(layer "F.Fab")
		)
		(fp_line
			(start 0.120396 0.2794)
			(end -0.12065 0.2794)
			(stroke
				(width 0.1)
				(type default)
			)
			(layer "F.Fab")
		)
		(fp_line
			(start -0.12065 0.2794)
			(end -0.12065 0.3048)
			(stroke
				(width 0.1)
				(type default)
			)
			(layer "F.Fab")
		)
		(fp_line
			(start 0.67945 0.3048)
			(end 0.120396 0.3048)
			(stroke
				(width 0.1)
				(type default)
			)
			(layer "F.Fab")
		)
		(fp_line
			(start 0.120396 0.3048)
			(end 0.120396 0.2794)
			(stroke
				(width 0.1)
				(type default)
			)
			(layer "F.Fab")
		)
		(fp_line
			(start -0.12065 0.3048)
			(end -0.67945 0.3048)
			(stroke
				(width 0.1)
				(type default)
			)
			(layer "F.Fab")
		)
		(fp_line
			(start -0.67945 0.3048)
			(end -0.67945 -0.305054)
			(stroke
				(width 0.1)
				(type default)
			)
			(layer "F.Fab")
		)
		(pad "1" smd circle
			(at -0.40005 0 90)
			(size 0 0)
			(layers "F.Cu" "F.Mask" "F.Paste")
			(net "P12V_SSD11_CO_ILIMIT")
		)
		(pad "2" smd circle
			(at 0.40005 0 90)
			(size 0 0)
			(layers "F.Cu" "F.Mask" "F.Paste")
			(net "GND")
		)
	)
	(footprint ""
		(layer "F.Cu")
		(at 380.16688 -52.543456 180)
		(property "Reference" "PC562"
			(at 0 0 180)
			(layer "F.SilkS")
			(hide yes)
			(effects
				(font
					(size 1.27 1.27)
				)
			)
		)
		(property "Value" ""
			(at 0 0 180)
			(layer "F.Fab")
			(effects
				(font
					(size 1.27 1.27)
				)
			)
		)
		(duplicate_pad_numbers_are_jumpers no)
		(fp_line
			(start 0.7874 0.4064)
			(end -0.7874 0.4064)
			(stroke
				(width 0.1524)
				(type default)
			)
			(layer "F.SilkS")
		)
		(fp_line
			(start 0.7874 -0.4064)
			(end 0.7874 0.4064)
			(stroke
				(width 0.1524)
				(type default)
			)
			(layer "F.SilkS")
		)
		(fp_line
			(start -0.7874 0.4064)
			(end -0.7874 -0.4064)
			(stroke
				(width 0.1524)
				(type default)
			)
			(layer "F.SilkS")
		)
		(fp_line
			(start -0.7874 -0.4064)
			(end 0.7874 -0.4064)
			(stroke
				(width 0.1524)
				(type default)
			)
			(layer "F.SilkS")
		)
		(fp_line
			(start 0.67945 0.3048)
			(end 0.120396 0.3048)
			(stroke
				(width 0.1)
				(type default)
			)
			(layer "F.Fab")
		)
		(fp_line
			(start 0.67945 -0.3048)
			(end 0.67945 0.3048)
			(stroke
				(width 0.1)
				(type default)
			)
			(layer "F.Fab")
		)
		(fp_line
			(start 0.12065 -0.2794)
			(end 0.12065 -0.3048)
			(stroke
				(width 0.1)
				(type default)
			)
			(layer "F.Fab")
		)
		(fp_line
			(start 0.12065 -0.3048)
			(end 0.67945 -0.3048)
			(stroke
				(width 0.1)
				(type default)
			)
			(layer "F.Fab")
		)
		(fp_line
			(start 0.120396 0.3048)
			(end 0.120396 0.2794)
			(stroke
				(width 0.1)
				(type default)
			)
			(layer "F.Fab")
		)
		(fp_line
			(start 0.120396 0.2794)
			(end -0.12065 0.2794)
			(stroke
				(width 0.1)
				(type default)
			)
			(layer "F.Fab")
		)
		(fp_line
			(start -0.12065 0.3048)
			(end -0.67945 0.3048)
			(stroke
				(width 0.1)
				(type default)
			)
			(layer "F.Fab")
		)
		(fp_line
			(start -0.12065 0.2794)
			(end -0.12065 0.3048)
			(stroke
				(width 0.1)
				(type default)
			)
			(layer "F.Fab")
		)
		(fp_line
			(start -0.12065 -0.2794)
			(end 0.12065 -0.2794)
			(stroke
				(width 0.1)
				(type default)
			)
			(layer "F.Fab")
		)
		(fp_line
			(start -0.12065 -0.305054)
			(end -0.12065 -0.2794)
			(stroke
				(width 0.1)
				(type default)
			)
			(layer "F.Fab")
		)
		(fp_line
			(start -0.67945 0.3048)
			(end -0.67945 -0.305054)
			(stroke
				(width 0.1)
				(type default)
			)
			(layer "F.Fab")
		)
		(fp_line
			(start -0.67945 -0.305054)
			(end -0.12065 -0.305054)
			(stroke
				(width 0.1)
				(type default)
			)
			(layer "F.Fab")
		)
		(pad "1" smd circle
			(at -0.40005 0 180)
			(size 0 0)
			(layers "F.Cu" "F.Mask" "F.Paste")
			(net "P3V3_SSD13")
		)
		(pad "2" smd circle
			(at 0.40005 0 180)
			(size 0 0)
			(layers "F.Cu" "F.Mask" "F.Paste")
			(net "GND")
		)
	)
)
